# SCM (Grand Teton) — schematic netlist excerpt (pin names and nets, part order shuffled) for the footprints in the layout excerpt that follows; sources: Cadence DE-HDL packaged netlist, KiCad conversion of 12092022_DA0F0TMDCD0_F0T_Management_Board_D_brd_V3_OCP.brd

R712  Q_RES  10K 1% EMPTY  pkg 0402LF  page 29 : A = P3V3_AUX ; B = USB3_MUX_PD

U37  PCA9517ADP  IC  pkg SMLF  page 28
  VCCA  = P3V3_AUX
  SCLA  = SMB_BMC_MM15_R1_SCL
  SDAA  = SMB_BMC_MM15_R1_SDA
  GND  = GND
  ENABLE  = DEBUG_PORT_PRSNT_BUF_EN
  SDAB  = SMB_DEBUG_AUX_LVC3_USB_R1_SDA
  SCLB  = SMB_DEBUG_AUX_LVC3_USB_R1_SCL
  VCCB  = P3V3_AUX

(kicad_pcb
	(version 20260206)
	(generator "pcbnew")
	(generator_version "10.0")
	(general
		(thickness 1.6)
		(legacy_teardrops no)
	)
	(paper "A4")
	(title_block
		(title "12092022_DA0F0TMDCD0_F0T_Management_Board_D_brd_V3_OCP.brd")
		(comment 1 "Grand Teton / footprints 1361-1362 of 1440")
	)
	(layers
		(0 "F.Cu" signal "TOP")
		(4 "In1.Cu" signal "GND")
		(6 "In2.Cu" signal "IN1")
		(8 "In3.Cu" signal "GND1")
		(10 "In4.Cu" signal "IN2")
		(12 "In5.Cu" signal "VCC")
		(14 "In6.Cu" signal "VCC1")
		(16 "In7.Cu" signal "IN3")
		(18 "In8.Cu" signal "GND2")
		(20 "In9.Cu" signal "IN4")
		(22 "In10.Cu" signal "GND3")
		(2 "B.Cu" signal "BOTTOM")
		(9 "F.Adhes" user "F.Adhesive")
		(11 "B.Adhes" user "B.Adhesive")
		(13 "F.Paste" user "Package Geometry/Pastemask Top")
		(15 "B.Paste" user "Package Geometry/Pastemask Bottom")
		(5 "F.SilkS" user "Ref Des/Silkscreen Top")
		(7 "B.SilkS" user "Ref Des/Silkscreen Bottom")
		(1 "F.Mask" user "Board Geometry/Soldermask Top")
		(3 "B.Mask" user "Board Geometry/Soldermask Bottom")
		(17 "Dwgs.User" user "User.Drawings")
		(19 "Cmts.User" user "User.Comments")
		(21 "Eco1.User" user "User.Eco1")
		(23 "Eco2.User" user "User.Eco2")
		(25 "Edge.Cuts" user "Board Geometry/Outline")
		(27 "Margin" user)
		(31 "F.CrtYd" user "Package Geometry/Place Bound Top")
		(29 "B.CrtYd" user "Package Geometry/Place Bound Bottom")
		(35 "F.Fab" user "Ref Des/Assembly Top")
		(33 "B.Fab" user "Ref Des/Assembly Bottom")
	)
	(footprint ""
		(layer "B.Cu")
		(at 16.637 -65.151 -90)
		(property "Reference" "U37"
			(at 1.397 -2.13233 270)
			(unlocked yes)
			(layer "B.SilkS")
			(effects
				(font
					(size 0.7874 0.5842)
					(thickness 0.1524)
				)
				(justify left mirror)
			)
		)
		(property "Value" ""
			(at 0 0 90)
			(layer "B.Fab")
			(effects
				(font
					(size 1.27 1.27)
				)
				(justify mirror)
			)
		)
		(duplicate_pad_numbers_are_jumpers no)
		(fp_line
			(start -1.3208 1.525016)
			(end 1.3208 1.525016)
			(stroke
				(width 0.1524)
				(type default)
			)
			(layer "B.SilkS")
		)
		(fp_line
			(start 1.3208 1.525016)
			(end 1.3208 -1.525016)
			(stroke
				(width 0.1524)
				(type default)
			)
			(layer "B.SilkS")
		)
		(fp_line
			(start 0 -0.999998)
			(end -0.508 -1.525016)
			(stroke
				(width 0.1524)
				(type default)
			)
			(layer "B.SilkS")
		)
		(fp_line
			(start -1.3208 -1.525016)
			(end -1.3208 1.525016)
			(stroke
				(width 0.1524)
				(type default)
			)
			(layer "B.SilkS")
		)
		(fp_line
			(start -0.508 -1.525016)
			(end -1.3208 -1.525016)
			(stroke
				(width 0.1524)
				(type default)
			)
			(layer "B.SilkS")
		)
		(fp_line
			(start 0.508 -1.525016)
			(end 0 -0.999998)
			(stroke
				(width 0.1524)
				(type default)
			)
			(layer "B.SilkS")
		)
		(fp_line
			(start 1.3208 -1.525016)
			(end 0.508 -1.525016)
			(stroke
				(width 0.1524)
				(type default)
			)
			(layer "B.SilkS")
		)
		(fp_poly
			(pts
				(xy 3.175 -1.016) (xy 3.937 -0.635) (xy 3.937 -1.397)
			)
			(stroke
				(width 0)
				(type default)
			)
			(fill yes)
			(layer "B.SilkS")
		)
		(fp_line
			(start -1.524 1.5494)
			(end 1.5494 1.5494)
			(stroke
				(width 0.1)
				(type default)
			)
			(layer "B.Fab")
		)
		(fp_line
			(start 1.5494 1.5494)
			(end 1.5494 1.203706)
			(stroke
				(width 0.1)
				(type default)
			)
			(layer "B.Fab")
		)
		(fp_line
			(start -3.0353 1.208786)
			(end -1.524 1.208786)
			(stroke
				(width 0.1)
				(type default)
			)
			(layer "B.Fab")
		)
		(fp_line
			(start -1.524 1.208786)
			(end -1.524 1.5494)
			(stroke
				(width 0.1)
				(type default)
			)
			(layer "B.Fab")
		)
		(fp_line
			(start 1.5494 1.203706)
			(end 3.037078 1.203706)
			(stroke
				(width 0.1)
				(type default)
			)
			(layer "B.Fab")
		)
		(fp_line
			(start 3.037078 1.203706)
			(end 3.037078 -1.20777)
			(stroke
				(width 0.1)
				(type default)
			)
			(layer "B.Fab")
		)
		(fp_line
			(start -3.0353 -1.20777)
			(end -3.0353 1.208786)
			(stroke
				(width 0.1)
				(type default)
			)
			(layer "B.Fab")
		)
		(fp_line
			(start -1.524 -1.20777)
			(end -3.0353 -1.20777)
			(stroke
				(width 0.1)
				(type default)
			)
			(layer "B.Fab")
		)
		(fp_line
			(start 1.524 -1.20777)
			(end 1.524 -1.524)
			(stroke
				(width 0.1)
				(type default)
			)
			(layer "B.Fab")
		)
		(fp_line
			(start 3.037078 -1.20777)
			(end 1.524 -1.20777)
			(stroke
				(width 0.1)
				(type default)
			)
			(layer "B.Fab")
		)
		(fp_line
			(start -1.524 -1.524)
			(end -1.524 -1.20777)
			(stroke
				(width 0.1)
				(type default)
			)
			(layer "B.Fab")
		)
		(fp_line
			(start 1.524 -1.524)
			(end -1.524 -1.524)
			(stroke
				(width 0.1)
				(type default)
			)
			(layer "B.Fab")
		)
		(fp_poly
			(pts
				(xy 3.175 -1.016) (xy 3.937 -0.635) (xy 3.937 -1.397)
			)
			(stroke
				(width 0)
				(type default)
			)
			(fill yes)
			(layer "B.Fab")
		)
		(pad "1" smd rect
			(at 2.234946 -0.975106 180)
			(size 0.3556 1.4986)
			(layers "B.Cu" "B.Mask" "B.Paste")
			(net "P3V3_AUX")
		)
		(pad "2" smd rect
			(at 2.234946 -0.32512 180)
			(size 0.3556 1.4986)
			(layers "B.Cu" "B.Mask" "B.Paste")
			(net "SMB_BMC_MM15_R1_SCL")
		)
		(pad "3" smd rect
			(at 2.234946 0.32512 180)
			(size 0.3556 1.4986)
			(layers "B.Cu" "B.Mask" "B.Paste")
			(net "SMB_BMC_MM15_R1_SDA")
		)
		(pad "4" smd rect
			(at 2.234946 0.975106 180)
			(size 0.3556 1.4986)
			(layers "B.Cu" "B.Mask" "B.Paste")
			(net "GND")
		)
		(pad "5" smd rect
			(at -2.234946 0.975106 180)
			(size 0.3556 1.4986)
			(layers "B.Cu" "B.Mask" "B.Paste")
			(net "DEBUG_PORT_PRSNT_BUF_EN")
		)
		(pad "6" smd rect
			(at -2.234946 0.32512 180)
			(size 0.3556 1.4986)
			(layers "B.Cu" "B.Mask" "B.Paste")
			(net "SMB_DEBUG_AUX_LVC3_USB_R1_SDA")
		)
		(pad "7" smd rect
			(at -2.234946 -0.32512 180)
			(size 0.3556 1.4986)
			(layers "B.Cu" "B.Mask" "B.Paste")
			(net "SMB_DEBUG_AUX_LVC3_USB_R1_SCL")
		)
		(pad "8" smd rect
			(at -2.234946 -0.975106 180)
			(size 0.3556 1.4986)
			(layers "B.Cu" "B.Mask" "B.Paste")
			(net "P3V3_AUX")
		)
	)
	(footprint ""
		(layer "B.Cu")
		(at 44.8818 -88.4936 -90)
		(property "Reference" "R712"
			(at 0 0 90)
			(layer "B.SilkS")
			(hide yes)
			(effects
				(font
					(size 1.27 1.27)
				)
				(justify mirror)
			)
		)
		(property "Value" ""
			(at 0 0 90)
			(layer "B.Fab")
			(effects
				(font
					(size 1.27 1.27)
				)
				(justify mirror)
			)
		)
		(duplicate_pad_numbers_are_jumpers no)
		(fp_line
			(start -0.7874 0.4064)
			(end 0.7874 0.4064)
			(stroke
				(width 0.1524)
				(type default)
			)
			(layer "B.SilkS")
		)
		(fp_line
			(start 0.7874 0.4064)
			(end 0.7874 -0.4064)
			(stroke
				(width 0.1524)
				(type default)
			)
			(layer "B.SilkS")
		)
		(fp_line
			(start -0.7874 -0.4064)
			(end -0.7874 0.4064)
			(stroke
				(width 0.1524)
				(type default)
			)
			(layer "B.SilkS")
		)
		(fp_line
			(start 0.7874 -0.4064)
			(end -0.7874 -0.4064)
			(stroke
				(width 0.1524)
				(type default)
			)
			(layer "B.SilkS")
		)
		(fp_line
			(start -0.67945 0.3048)
			(end -0.120396 0.3048)
			(stroke
				(width 0.1)
				(type default)
			)
			(layer "B.Fab")
		)
		(fp_line
			(start -0.120396 0.3048)
			(end -0.120396 0.2794)
			(stroke
				(width 0.1)
				(type default)
			)
			(layer "B.Fab")
		)
		(fp_line
			(start 0.12065 0.3048)
			(end 0.67945 0.3048)
			(stroke
				(width 0.1)
				(type default)
			)
			(layer "B.Fab")
		)
		(fp_line
			(start 0.67945 0.3048)
			(end 0.67945 -0.305054)
			(stroke
				(width 0.1)
				(type default)
			)
			(layer "B.Fab")
		)
		(fp_line
			(start -0.120396 0.2794)
			(end 0.12065 0.2794)
			(stroke
				(width 0.1)
				(type default)
			)
			(layer "B.Fab")
		)
		(fp_line
			(start 0.12065 0.2794)
			(end 0.12065 0.3048)
			(stroke
				(width 0.1)
				(type default)
			)
			(layer "B.Fab")
		)
		(fp_line
			(start -0.12065 -0.2794)
			(end -0.12065 -0.3048)
			(stroke
				(width 0.1)
				(type default)
			)
			(layer "B.Fab")
		)
		(fp_line
			(start 0.12065 -0.2794)
			(end -0.12065 -0.2794)
			(stroke
				(width 0.1)
				(type default)
			)
			(layer "B.Fab")
		)
		(fp_line
			(start -0.67945 -0.3048)
			(end -0.67945 0.3048)
			(stroke
				(width 0.1)
				(type default)
			)
			(layer "B.Fab")
		)
		(fp_line
			(start -0.12065 -0.3048)
			(end -0.67945 -0.3048)
			(stroke
				(width 0.1)
				(type default)
			)
			(layer "B.Fab")
		)
		(fp_line
			(start 0.12065 -0.305054)
			(end 0.12065 -0.2794)
			(stroke
				(width 0.1)
				(type default)
			)
			(layer "B.Fab")
		)
		(fp_line
			(start 0.67945 -0.305054)
			(end 0.12065 -0.305054)
			(stroke
				(width 0.1)
				(type default)
			)
			(layer "B.Fab")
		)
		(pad "1" smd circle
			(at 0.40005 0 90)
			(size 0 0)
			(layers "B.Cu" "B.Mask" "B.Paste")
			(net "P3V3_AUX")
		)
		(pad "2" smd circle
			(at -0.40005 0 90)
			(size 0 0)
			(layers "B.Cu" "B.Mask" "B.Paste")
			(net "USB3_MUX_PD")
		)
	)
)
